(kicad_pcb
	(version 20260206)
	(generator "pcbnew")
	(generator_version "10.0")
	(general
		(thickness 1.6)
		(legacy_teardrops no)
	)
	(paper "A4")
	(title_block
		(title "04192023_DAF0TMB3IC0_F0TG_MB_C_brd_V02_OCP.brd")
		(comment 1 "Grand Teton / footprints 5886-5890 of 8354")
	)
	(layers
		(0 "F.Cu" signal "TOP")
		(4 "In1.Cu" signal "GND")
		(6 "In2.Cu" signal "IN1")
		(8 "In3.Cu" signal "GND1")
		(10 "In4.Cu" signal "IN2")
		(12 "In5.Cu" signal "GND2")
		(14 "In6.Cu" signal "IN3")
		(16 "In7.Cu" signal "GND3")
		(18 "In8.Cu" signal "VCC")
		(20 "In9.Cu" signal "VCC1")
		(22 "In10.Cu" signal "GND4")
		(24 "In11.Cu" signal "IN4")
		(26 "In12.Cu" signal "GND5")
		(28 "In13.Cu" signal "IN5")
		(30 "In14.Cu" signal "GND6")
		(32 "In15.Cu" signal "IN6")
		(34 "In16.Cu" signal "GND7")
		(2 "B.Cu" signal "BOTTOM")
		(9 "F.Adhes" user "F.Adhesive")
		(11 "B.Adhes" user "B.Adhesive")
		(13 "F.Paste" user "Package Geometry/Pastemask Top")
		(15 "B.Paste" user "Package Geometry/Pastemask Bottom")
		(5 "F.SilkS" user "Ref Des/Silkscreen Top")
		(7 "B.SilkS" user "Ref Des/Silkscreen Bottom")
		(1 "F.Mask" user "Board Geometry/Soldermask Top")
		(3 "B.Mask" user "Board Geometry/Soldermask Bottom")
		(17 "Dwgs.User" user "User.Drawings")
		(19 "Cmts.User" user "User.Comments")
		(21 "Eco1.User" user "User.Eco1")
		(23 "Eco2.User" user "User.Eco2")
		(25 "Edge.Cuts" user "Board Geometry/Outline")
		(27 "Margin" user)
		(31 "F.CrtYd" user "Package Geometry/Place Bound Top")
		(29 "B.CrtYd" user "Package Geometry/Place Bound Bottom")
		(35 "F.Fab" user "Ref Des/Assembly Top")
		(33 "B.Fab" user "Ref Des/Assembly Bottom")
	)
	(footprint ""
		(layer "B.Cu")
		(at 107.101386 -248.479564 180)
		(property "Reference" "C2314"
			(at 0 0 0)
			(layer "B.SilkS")
			(hide yes)
			(effects
				(font
					(size 1.27 1.27)
				)
				(justify mirror)
			)
		)
		(property "Value" ""
			(at 0 0 0)
			(layer "B.Fab")
			(effects
				(font
					(size 1.27 1.27)
				)
				(justify mirror)
			)
		)
		(duplicate_pad_numbers_are_jumpers no)
		(fp_line
			(start 0.7874 0.4064)
			(end 0.7874 -0.4064)
			(stroke
				(width 0.1524)
				(type default)
			)
			(layer "B.SilkS")
		)
		(fp_line
			(start 0.7874 -0.4064)
			(end -0.7874 -0.4064)
			(stroke
				(width 0.1524)
				(type default)
			)
			(layer "B.SilkS")
		)
		(fp_line
			(start -0.7874 0.4064)
			(end 0.7874 0.4064)
			(stroke
				(width 0.1524)
				(type default)
			)
			(layer "B.SilkS")
		)
		(fp_line
			(start -0.7874 -0.4064)
			(end -0.7874 0.4064)
			(stroke
				(width 0.1524)
				(type default)
			)
			(layer "B.SilkS")
		)
		(fp_line
			(start 0.67945 0.3048)
			(end 0.67945 -0.305054)
			(stroke
				(width 0.1)
				(type default)
			)
			(layer "B.Fab")
		)
		(fp_line
			(start 0.67945 -0.305054)
			(end 0.12065 -0.305054)
			(stroke
				(width 0.1)
				(type default)
			)
			(layer "B.Fab")
		)
		(fp_line
			(start 0.12065 0.3048)
			(end 0.67945 0.3048)
			(stroke
				(width 0.1)
				(type default)
			)
			(layer "B.Fab")
		)
		(fp_line
			(start 0.12065 0.2794)
			(end 0.12065 0.3048)
			(stroke
				(width 0.1)
				(type default)
			)
			(layer "B.Fab")
		)
		(fp_line
			(start 0.12065 -0.2794)
			(end -0.12065 -0.2794)
			(stroke
				(width 0.1)
				(type default)
			)
			(layer "B.Fab")
		)
		(fp_line
			(start 0.12065 -0.305054)
			(end 0.12065 -0.2794)
			(stroke
				(width 0.1)
				(type default)
			)
			(layer "B.Fab")
		)
		(fp_line
			(start -0.120396 0.3048)
			(end -0.120396 0.2794)
			(stroke
				(width 0.1)
				(type default)
			)
			(layer "B.Fab")
		)
		(fp_line
			(start -0.120396 0.2794)
			(end 0.12065 0.2794)
			(stroke
				(width 0.1)
				(type default)
			)
			(layer "B.Fab")
		)
		(fp_line
			(start -0.12065 -0.2794)
			(end -0.12065 -0.3048)
			(stroke
				(width 0.1)
				(type default)
			)
			(layer "B.Fab")
		)
		(fp_line
			(start -0.12065 -0.3048)
			(end -0.67945 -0.3048)
			(stroke
				(width 0.1)
				(type default)
			)
			(layer "B.Fab")
		)
		(fp_line
			(start -0.67945 0.3048)
			(end -0.120396 0.3048)
			(stroke
				(width 0.1)
				(type default)
			)
			(layer "B.Fab")
		)
		(fp_line
			(start -0.67945 -0.3048)
			(end -0.67945 0.3048)
			(stroke
				(width 0.1)
				(type default)
			)
			(layer "B.Fab")
		)
		(pad "1" smd circle
			(at 0.40005 0)
			(size 0 0)
			(layers "B.Cu" "B.Mask" "B.Paste")
			(net "PVDDCR_CPU0_P1")
		)
		(pad "2" smd circle
			(at -0.40005 0)
			(size 0 0)
			(layers "B.Cu" "B.Mask" "B.Paste")
			(net "GND")
		)
	)
	(footprint ""
		(layer "B.Cu")
		(at 228.505258 -323.263768 180)
		(property "Reference" "C1092"
			(at 0 0 0)
			(layer "B.SilkS")
			(hide yes)
			(effects
				(font
					(size 1.27 1.27)
				)
				(justify mirror)
			)
		)
		(property "Value" ""
			(at 0 0 0)
			(layer "B.Fab")
			(effects
				(font
					(size 1.27 1.27)
				)
				(justify mirror)
			)
		)
		(duplicate_pad_numbers_are_jumpers no)
		(fp_line
			(start 0.7874 0.4064)
			(end 0.7874 -0.4064)
			(stroke
				(width 0.1524)
				(type default)
			)
			(layer "B.SilkS")
		)
		(fp_line
			(start 0.7874 -0.4064)
			(end -0.7874 -0.4064)
			(stroke
				(width 0.1524)
				(type default)
			)
			(layer "B.SilkS")
		)
		(fp_line
			(start -0.7874 0.4064)
			(end 0.7874 0.4064)
			(stroke
				(width 0.1524)
				(type default)
			)
			(layer "B.SilkS")
		)
		(fp_line
			(start -0.7874 -0.4064)
			(end -0.7874 0.4064)
			(stroke
				(width 0.1524)
				(type default)
			)
			(layer "B.SilkS")
		)
		(fp_line
			(start 0.67945 0.3048)
			(end 0.67945 -0.305054)
			(stroke
				(width 0.1)
				(type default)
			)
			(layer "B.Fab")
		)
		(fp_line
			(start 0.67945 -0.305054)
			(end 0.12065 -0.305054)
			(stroke
				(width 0.1)
				(type default)
			)
			(layer "B.Fab")
		)
		(fp_line
			(start 0.12065 0.3048)
			(end 0.67945 0.3048)
			(stroke
				(width 0.1)
				(type default)
			)
			(layer "B.Fab")
		)
		(fp_line
			(start 0.12065 0.2794)
			(end 0.12065 0.3048)
			(stroke
				(width 0.1)
				(type default)
			)
			(layer "B.Fab")
		)
		(fp_line
			(start 0.12065 -0.2794)
			(end -0.12065 -0.2794)
			(stroke
				(width 0.1)
				(type default)
			)
			(layer "B.Fab")
		)
		(fp_line
			(start 0.12065 -0.305054)
			(end 0.12065 -0.2794)
			(stroke
				(width 0.1)
				(type default)
			)
			(layer "B.Fab")
		)
		(fp_line
			(start -0.120396 0.3048)
			(end -0.120396 0.2794)
			(stroke
				(width 0.1)
				(type default)
			)
			(layer "B.Fab")
		)
		(fp_line
			(start -0.120396 0.2794)
			(end 0.12065 0.2794)
			(stroke
				(width 0.1)
				(type default)
			)
			(layer "B.Fab")
		)
		(fp_line
			(start -0.12065 -0.2794)
			(end -0.12065 -0.3048)
			(stroke
				(width 0.1)
				(type default)
			)
			(layer "B.Fab")
		)
		(fp_line
			(start -0.12065 -0.3048)
			(end -0.67945 -0.3048)
			(stroke
				(width 0.1)
				(type default)
			)
			(layer "B.Fab")
		)
		(fp_line
			(start -0.67945 0.3048)
			(end -0.120396 0.3048)
			(stroke
				(width 0.1)
				(type default)
			)
			(layer "B.Fab")
		)
		(fp_line
			(start -0.67945 -0.3048)
			(end -0.67945 0.3048)
			(stroke
				(width 0.1)
				(type default)
			)
			(layer "B.Fab")
		)
		(pad "1" smd circle
			(at 0.40005 0)
			(size 0 0)
			(layers "B.Cu" "B.Mask" "B.Paste")
			(net "P1V8_AUX_ADC_TIC")
		)
		(pad "2" smd circle
			(at -0.40005 0)
			(size 0 0)
			(layers "B.Cu" "B.Mask" "B.Paste")
			(net "GND")
		)
	)
	(footprint ""
		(layer "B.Cu")
		(at 106.621834 -249.368564 180)
		(property "Reference" "C2294"
			(at 0 0 0)
			(layer "B.SilkS")
			(hide yes)
			(effects
				(font
					(size 1.27 1.27)
				)
				(justify mirror)
			)
		)
		(property "Value" ""
			(at 0 0 0)
			(layer "B.Fab")
			(effects
				(font
					(size 1.27 1.27)
				)
				(justify mirror)
			)
		)
		(duplicate_pad_numbers_are_jumpers no)
		(fp_line
			(start 0.7874 0.4064)
			(end 0.7874 -0.4064)
			(stroke
				(width 0.1524)
				(type default)
			)
			(layer "B.SilkS")
		)
		(fp_line
			(start 0.7874 -0.4064)
			(end -0.7874 -0.4064)
			(stroke
				(width 0.1524)
				(type default)
			)
			(layer "B.SilkS")
		)
		(fp_line
			(start -0.7874 0.4064)
			(end 0.7874 0.4064)
			(stroke
				(width 0.1524)
				(type default)
			)
			(layer "B.SilkS")
		)
		(fp_line
			(start -0.7874 -0.4064)
			(end -0.7874 0.4064)
			(stroke
				(width 0.1524)
				(type default)
			)
			(layer "B.SilkS")
		)
		(fp_line
			(start 0.67945 0.3048)
			(end 0.67945 -0.305054)
			(stroke
				(width 0.1)
				(type default)
			)
			(layer "B.Fab")
		)
		(fp_line
			(start 0.67945 -0.305054)
			(end 0.12065 -0.305054)
			(stroke
				(width 0.1)
				(type default)
			)
			(layer "B.Fab")
		)
		(fp_line
			(start 0.12065 0.3048)
			(end 0.67945 0.3048)
			(stroke
				(width 0.1)
				(type default)
			)
			(layer "B.Fab")
		)
		(fp_line
			(start 0.12065 0.2794)
			(end 0.12065 0.3048)
			(stroke
				(width 0.1)
				(type default)
			)
			(layer "B.Fab")
		)
		(fp_line
			(start 0.12065 -0.2794)
			(end -0.12065 -0.2794)
			(stroke
				(width 0.1)
				(type default)
			)
			(layer "B.Fab")
		)
		(fp_line
			(start 0.12065 -0.305054)
			(end 0.12065 -0.2794)
			(stroke
				(width 0.1)
				(type default)
			)
			(layer "B.Fab")
		)
		(fp_line
			(start -0.120396 0.3048)
			(end -0.120396 0.2794)
			(stroke
				(width 0.1)
				(type default)
			)
			(layer "B.Fab")
		)
		(fp_line
			(start -0.120396 0.2794)
			(end 0.12065 0.2794)
			(stroke
				(width 0.1)
				(type default)
			)
			(layer "B.Fab")
		)
		(fp_line
			(start -0.12065 -0.2794)
			(end -0.12065 -0.3048)
			(stroke
				(width 0.1)
				(type default)
			)
			(layer "B.Fab")
		)
		(fp_line
			(start -0.12065 -0.3048)
			(end -0.67945 -0.3048)
			(stroke
				(width 0.1)
				(type default)
			)
			(layer "B.Fab")
		)
		(fp_line
			(start -0.67945 0.3048)
			(end -0.120396 0.3048)
			(stroke
				(width 0.1)
				(type default)
			)
			(layer "B.Fab")
		)
		(fp_line
			(start -0.67945 -0.3048)
			(end -0.67945 0.3048)
			(stroke
				(width 0.1)
				(type default)
			)
			(layer "B.Fab")
		)
		(pad "1" smd circle
			(at 0.40005 0)
			(size 0 0)
			(layers "B.Cu" "B.Mask" "B.Paste")
			(net "PVDDCR_CPU0_P1")
		)
		(pad "2" smd circle
			(at -0.40005 0)
			(size 0 0)
			(layers "B.Cu" "B.Mask" "B.Paste")
			(net "GND")
		)
	)
	(footprint ""
		(layer "B.Cu")
		(at 104.180386 -268.418564)
		(property "Reference" "C2350"
			(at 0 0 0)
			(layer "B.SilkS")
			(hide yes)
			(effects
				(font
					(size 1.27 1.27)
				)
				(justify mirror)
			)
		)
		(property "Value" ""
			(at 0 0 0)
			(layer "B.Fab")
			(effects
				(font
					(size 1.27 1.27)
				)
				(justify mirror)
			)
		)
		(duplicate_pad_numbers_are_jumpers no)
		(fp_line
			(start -0.7874 -0.4064)
			(end -0.7874 0.4064)
			(stroke
				(width 0.1524)
				(type default)
			)
			(layer "B.SilkS")
		)
		(fp_line
			(start -0.7874 0.4064)
			(end 0.7874 0.4064)
			(stroke
				(width 0.1524)
				(type default)
			)
			(layer "B.SilkS")
		)
		(fp_line
			(start 0.7874 -0.4064)
			(end -0.7874 -0.4064)
			(stroke
				(width 0.1524)
				(type default)
			)
			(layer "B.SilkS")
		)
		(fp_line
			(start 0.7874 0.4064)
			(end 0.7874 -0.4064)
			(stroke
				(width 0.1524)
				(type default)
			)
			(layer "B.SilkS")
		)
		(fp_line
			(start -0.67945 -0.3048)
			(end -0.67945 0.3048)
			(stroke
				(width 0.1)
				(type default)
			)
			(layer "B.Fab")
		)
		(fp_line
			(start -0.67945 0.3048)
			(end -0.120396 0.3048)
			(stroke
				(width 0.1)
				(type default)
			)
			(layer "B.Fab")
		)
		(fp_line
			(start -0.12065 -0.3048)
			(end -0.67945 -0.3048)
			(stroke
				(width 0.1)
				(type default)
			)
			(layer "B.Fab")
		)
		(fp_line
			(start -0.12065 -0.2794)
			(end -0.12065 -0.3048)
			(stroke
				(width 0.1)
				(type default)
			)
			(layer "B.Fab")
		)
		(fp_line
			(start -0.120396 0.2794)
			(end 0.12065 0.2794)
			(stroke
				(width 0.1)
				(type default)
			)
			(layer "B.Fab")
		)
		(fp_line
			(start -0.120396 0.3048)
			(end -0.120396 0.2794)
			(stroke
				(width 0.1)
				(type default)
			)
			(layer "B.Fab")
		)
		(fp_line
			(start 0.12065 -0.305054)
			(end 0.12065 -0.2794)
			(stroke
				(width 0.1)
				(type default)
			)
			(layer "B.Fab")
		)
		(fp_line
			(start 0.12065 -0.2794)
			(end -0.12065 -0.2794)
			(stroke
				(width 0.1)
				(type default)
			)
			(layer "B.Fab")
		)
		(fp_line
			(start 0.12065 0.2794)
			(end 0.12065 0.3048)
			(stroke
				(width 0.1)
				(type default)
			)
			(layer "B.Fab")
		)
		(fp_line
			(start 0.12065 0.3048)
			(end 0.67945 0.3048)
			(stroke
				(width 0.1)
				(type default)
			)
			(layer "B.Fab")
		)
		(fp_line
			(start 0.67945 -0.305054)
			(end 0.12065 -0.305054)
			(stroke
				(width 0.1)
				(type default)
			)
			(layer "B.Fab")
		)
		(fp_line
			(start 0.67945 0.3048)
			(end 0.67945 -0.305054)
			(stroke
				(width 0.1)
				(type default)
			)
			(layer "B.Fab")
		)
		(pad "1" smd circle
			(at 0.40005 0 180)
			(size 0 0)
			(layers "B.Cu" "B.Mask" "B.Paste")
			(net "PVDDCR_CPU1_P1")
		)
		(pad "2" smd circle
			(at -0.40005 0 180)
			(size 0 0)
			(layers "B.Cu" "B.Mask" "B.Paste")
			(net "GND")
		)
	)
	(footprint ""
		(layer "B.Cu")
		(at 366.288574 -2.537206)
		(property "Reference" "J117"
			(at 4.34594 1.464056 270)
			(unlocked yes)
			(layer "B.SilkS")
			(effects
				(font
					(size 0.7874 0.5842)
					(thickness 0.1524)
				)
				(justify left mirror)
			)
		)
		(property "Value" ""
			(at 0 0 0)
			(layer "B.Fab")
			(effects
				(font
					(size 1.27 1.27)
				)
				(justify mirror)
			)
		)
		(duplicate_pad_numbers_are_jumpers no)
		(fp_line
			(start -1.2192 -2.06756)
			(end -1.2192 2.06756)
			(stroke
				(width 0.1524)
				(type default)
			)
			(layer "B.SilkS")
		)
		(fp_line
			(start -1.2192 2.06756)
			(end 1.2192 2.06756)
			(stroke
				(width 0.1524)
				(type default)
			)
			(layer "B.SilkS")
		)
		(fp_line
			(start 1.2192 -2.06756)
			(end -1.2192 -2.06756)
			(stroke
				(width 0.1524)
				(type default)
			)
			(layer "B.SilkS")
		)
		(fp_line
			(start 1.2192 2.06756)
			(end 1.2192 -2.06756)
			(stroke
				(width 0.1524)
				(type default)
			)
			(layer "B.SilkS")
		)
		(pad "" np_thru_hole circle
			(at -3.4671 -1.27 270)
			(size 1.0414 1.0414)
			(drill 1.0414)
			(layers "*.Cu" "*.Mask")
			(clearance 0.381)
			(thermal_gap 0.381)
		)
		(pad "" np_thru_hole circle
			(at -3.4671 1.27 270)
			(size 1.0414 1.0414)
			(drill 1.0414)
			(layers "*.Cu" "*.Mask")
			(clearance 0.381)
			(thermal_gap 0.381)
		)
		(pad "" np_thru_hole circle
			(at 2.8829 -1.27 270)
			(size 1.0414 1.0414)
			(drill 1.0414)
			(layers "*.Cu" "*.Mask")
			(clearance 0.381)
			(thermal_gap 0.381)
		)
		(pad "" np_thru_hole circle
			(at 2.8829 1.27 270)
			(size 1.0414 1.0414)
			(drill 1.0414)
			(layers "*.Cu" "*.Mask")
			(clearance 0.381)
			(thermal_gap 0.381)
		)
		(pad "1" smd rect
			(at -0.8255 -0.249936 270)
			(size 0.3048 0.508)
			(layers "B.Cu" "B.Mask" "B.Paste")
			(net "DELTA_L_85_5INCH_IN6_DN")
		)
		(pad "2" smd rect
			(at -0.8255 0.249936 270)
			(size 0.3048 0.508)
			(layers "B.Cu" "B.Mask" "B.Paste")
			(net "DELTA_L_85_5INCH_IN6_DP")
		)
		(pad "3" smd circle
			(at 0 0 180)
			(size 0 0)
			(layers "B.Cu" "B.Mask" "B.Paste")
			(net "DELTA_L_GND_1")
		)
		(zone
			(layers "F.Cu" "B.Cu" "In1.Cu" "In2.Cu" "In3.Cu" "In4.Cu" "In5.Cu" "In6.Cu"
				"In7.Cu" "In8.Cu" "In9.Cu" "In10.Cu" "In11.Cu" "In12.Cu" "In13.Cu" "In14.Cu"
				"In15.Cu" "In16.Cu"
			)
			(hatch none 0.5)
			(connect_pads
				(clearance 0)
			)
			(min_thickness 0.25)
			(keepout
				(tracks not_allowed)
				(vias allowed)
				(pads allowed)
				(copperpour not_allowed)
				(footprints allowed)
			)
			(placement
				(enabled no)
				(sheetname "")
			)
			(fill
				(thermal_gap 0.5)
				(thermal_bridge_width 0.5)
				(island_removal_mode 0)
			)
			(polygon
				(pts
					(arc
						(start 363.748574 -3.807206)
						(mid 361.894374 -3.807206)
						(end 363.748574 -3.807206)
					)
				)
			)
		)
		(zone
			(layers "F.Cu" "B.Cu" "In1.Cu" "In2.Cu" "In3.Cu" "In4.Cu" "In5.Cu" "In6.Cu"
				"In7.Cu" "In8.Cu" "In9.Cu" "In10.Cu" "In11.Cu" "In12.Cu" "In13.Cu" "In14.Cu"
				"In15.Cu" "In16.Cu"
			)
			(hatch none 0.5)
			(connect_pads
				(clearance 0)
			)
			(min_thickness 0.25)
			(keepout
				(tracks not_allowed)
				(vias allowed)
				(pads allowed)
				(copperpour not_allowed)
				(footprints allowed)
			)
			(placement
				(enabled no)
				(sheetname "")
			)
			(fill
				(thermal_gap 0.5)
				(thermal_bridge_width 0.5)
				(island_removal_mode 0)
			)
			(polygon
				(pts
					(arc
						(start 363.748574 -1.267206)
						(mid 361.894374 -1.267206)
						(end 363.748574 -1.267206)
					)
				)
			)
		)
		(zone
			(layers "F.Cu" "B.Cu" "In1.Cu" "In2.Cu" "In3.Cu" "In4.Cu" "In5.Cu" "In6.Cu"
				"In7.Cu" "In8.Cu" "In9.Cu" "In10.Cu" "In11.Cu" "In12.Cu" "In13.Cu" "In14.Cu"
				"In15.Cu" "In16.Cu"
			)
			(hatch none 0.5)
			(connect_pads
				(clearance 0)
			)
			(min_thickness 0.25)
			(keepout
				(tracks not_allowed)
				(vias allowed)
				(pads allowed)
				(copperpour not_allowed)
				(footprints allowed)
			)
			(placement
				(enabled no)
				(sheetname "")
			)
			(fill
				(thermal_gap 0.5)
				(thermal_bridge_width 0.5)
				(island_removal_mode 0)
			)
			(polygon
				(pts
					(arc
						(start 370.098574 -3.807206)
						(mid 368.244374 -3.807206)
						(end 370.098574 -3.807206)
					)
				)
			)
		)
		(zone
			(layers "F.Cu" "B.Cu" "In1.Cu" "In2.Cu" "In3.Cu" "In4.Cu" "In5.Cu" "In6.Cu"
				"In7.Cu" "In8.Cu" "In9.Cu" "In10.Cu" "In11.Cu" "In12.Cu" "In13.Cu" "In14.Cu"
				"In15.Cu" "In16.Cu"
			)
			(hatch none 0.5)
			(connect_pads
				(clearance 0)
			)
			(min_thickness 0.25)
			(keepout
				(tracks not_allowed)
				(vias allowed)
				(pads allowed)
				(copperpour not_allowed)
				(footprints allowed)
			)
			(placement
				(enabled no)
				(sheetname "")
			)
			(fill
				(thermal_gap 0.5)
				(thermal_bridge_width 0.5)
				(island_removal_mode 0)
			)
			(polygon
				(pts
					(arc
						(start 370.098574 -1.267206)
						(mid 368.244374 -1.267206)
						(end 370.098574 -1.267206)
					)
				)
			)
		)
		(zone
			(layer "B.Cu")
			(hatch none 0.5)
			(connect_pads
				(clearance 0)
			)
			(min_thickness 0.25)
			(keepout
				(tracks not_allowed)
				(vias allowed)
				(pads allowed)
				(copperpour not_allowed)
				(footprints allowed)
			)
			(placement
				(enabled no)
				(sheetname "")
			)
			(fill
				(thermal_gap 0.5)
				(thermal_bridge_width 0.5)
				(island_removal_mode 0)
			)
			(polygon
				(pts
					(xy 365.170974 -3.085846) (xy 365.170974 -2.990342) (xy 365.767874 -2.990342) (xy 365.767874 -2.583942)
					(xy 365.170974 -2.583942) (xy 365.170974 -2.49047) (xy 365.767874 -2.49047) (xy 365.767874 -2.08407)
					(xy 365.170974 -2.08407) (xy 365.170974 -1.988566) (xy 365.869474 -1.988566) (xy 365.869474 -3.085846)
				)
			)
		)
	)
)
